# SCM (Grand Teton) — schematic netlist excerpt (pin names and nets, part order shuffled) for the footprints in the layout excerpt that follows; sources: Cadence DE-HDL packaged netlist, KiCad conversion of 12092022_DA0F0TMDCD0_F0T_Management_Board_D_brd_V3_OCP.brd

C278  Q_CAP  0.1UF 25V 10% X7R  pkg 0402  page 55 : A = P12V_AUX ; B = GND

(kicad_pcb
	(version 20260206)
	(generator "pcbnew")
	(generator_version "10.0")
	(general
		(thickness 1.6)
		(legacy_teardrops no)
	)
	(paper "A4")
	(title_block
		(title "12092022_DA0F0TMDCD0_F0T_Management_Board_D_brd_V3_OCP.brd")
		(comment 1 "Grand Teton / footprints 127-127 of 1440")
	)
	(layers
		(0 "F.Cu" signal "TOP")
		(4 "In1.Cu" signal "GND")
		(6 "In2.Cu" signal "IN1")
		(8 "In3.Cu" signal "GND1")
		(10 "In4.Cu" signal "IN2")
		(12 "In5.Cu" signal "VCC")
		(14 "In6.Cu" signal "VCC1")
		(16 "In7.Cu" signal "IN3")
		(18 "In8.Cu" signal "GND2")
		(20 "In9.Cu" signal "IN4")
		(22 "In10.Cu" signal "GND3")
		(2 "B.Cu" signal "BOTTOM")
		(9 "F.Adhes" user "F.Adhesive")
		(11 "B.Adhes" user "B.Adhesive")
		(13 "F.Paste" user "Package Geometry/Pastemask Top")
		(15 "B.Paste" user "Package Geometry/Pastemask Bottom")
		(5 "F.SilkS" user "Ref Des/Silkscreen Top")
		(7 "B.SilkS" user "Ref Des/Silkscreen Bottom")
		(1 "F.Mask" user "Board Geometry/Soldermask Top")
		(3 "B.Mask" user "Board Geometry/Soldermask Bottom")
		(17 "Dwgs.User" user "User.Drawings")
		(19 "Cmts.User" user "User.Comments")
		(21 "Eco1.User" user "User.Eco1")
		(23 "Eco2.User" user "User.Eco2")
		(25 "Edge.Cuts" user "Board Geometry/Outline")
		(27 "Margin" user)
		(31 "F.CrtYd" user "Package Geometry/Place Bound Top")
		(29 "B.CrtYd" user "Package Geometry/Place Bound Bottom")
		(35 "F.Fab" user "Ref Des/Assembly Top")
		(33 "B.Fab" user "Ref Des/Assembly Bottom")
	)
	(footprint ""
		(layer "F.Cu")
		(at 84.0486 -81.0006 -90)
		(property "Reference" "C278"
			(at 0 0 270)
			(layer "F.SilkS")
			(hide yes)
			(effects
				(font
					(size 1.27 1.27)
				)
			)
		)
		(property "Value" ""
			(at 0 0 270)
			(layer "F.Fab")
			(effects
				(font
					(size 1.27 1.27)
				)
			)
		)
		(duplicate_pad_numbers_are_jumpers no)
		(fp_line
			(start -0.7874 0.4064)
			(end -0.7874 -0.4064)
			(stroke
				(width 0.1524)
				(type default)
			)
			(layer "F.SilkS")
		)
		(fp_line
			(start 0.7874 0.4064)
			(end -0.7874 0.4064)
			(stroke
				(width 0.1524)
				(type default)
			)
			(layer "F.SilkS")
		)
		(fp_line
			(start -0.7874 -0.4064)
			(end 0.7874 -0.4064)
			(stroke
				(width 0.1524)
				(type default)
			)
			(layer "F.SilkS")
		)
		(fp_line
			(start 0.7874 -0.4064)
			(end 0.7874 0.4064)
			(stroke
				(width 0.1524)
				(type default)
			)
			(layer "F.SilkS")
		)
		(fp_line
			(start -0.67945 0.3048)
			(end -0.67945 -0.305054)
			(stroke
				(width 0.1)
				(type default)
			)
			(layer "F.Fab")
		)
		(fp_line
			(start -0.12065 0.3048)
			(end -0.67945 0.3048)
			(stroke
				(width 0.1)
				(type default)
			)
			(layer "F.Fab")
		)
		(fp_line
			(start 0.120396 0.3048)
			(end 0.120396 0.2794)
			(stroke
				(width 0.1)
				(type default)
			)
			(layer "F.Fab")
		)
		(fp_line
			(start 0.67945 0.3048)
			(end 0.120396 0.3048)
			(stroke
				(width 0.1)
				(type default)
			)
			(layer "F.Fab")
		)
		(fp_line
			(start -0.12065 0.2794)
			(end -0.12065 0.3048)
			(stroke
				(width 0.1)
				(type default)
			)
			(layer "F.Fab")
		)
		(fp_line
			(start 0.120396 0.2794)
			(end -0.12065 0.2794)
			(stroke
				(width 0.1)
				(type default)
			)
			(layer "F.Fab")
		)
		(fp_line
			(start -0.12065 -0.2794)
			(end 0.12065 -0.2794)
			(stroke
				(width 0.1)
				(type default)
			)
			(layer "F.Fab")
		)
		(fp_line
			(start 0.12065 -0.2794)
			(end 0.12065 -0.3048)
			(stroke
				(width 0.1)
				(type default)
			)
			(layer "F.Fab")
		)
		(fp_line
			(start 0.12065 -0.3048)
			(end 0.67945 -0.3048)
			(stroke
				(width 0.1)
				(type default)
			)
			(layer "F.Fab")
		)
		(fp_line
			(start 0.67945 -0.3048)
			(end 0.67945 0.3048)
			(stroke
				(width 0.1)
				(type default)
			)
			(layer "F.Fab")
		)
		(fp_line
			(start -0.67945 -0.305054)
			(end -0.12065 -0.305054)
			(stroke
				(width 0.1)
				(type default)
			)
			(layer "F.Fab")
		)
		(fp_line
			(start -0.12065 -0.305054)
			(end -0.12065 -0.2794)
			(stroke
				(width 0.1)
				(type default)
			)
			(layer "F.Fab")
		)
		(pad "1" smd circle
			(at -0.40005 0 270)
			(size 0 0)
			(layers "F.Cu" "F.Mask" "F.Paste")
			(net "P12V_AUX")
		)
		(pad "2" smd circle
			(at 0.40005 0 270)
			(size 0 0)
			(layers "F.Cu" "F.Mask" "F.Paste")
			(net "GND")
		)
	)
)
